(kicad_pcb
	(version 20260206)
	(generator "pcbnew")
	(generator_version "10.0")
	(general
		(thickness 1.6)
		(legacy_teardrops no)
	)
	(paper "A4")
	(title_block
		(title "01162023_DA0F0TEBIF0_F0T_Expander_BD_F_brd_V02_OCP.brd")
		(comment 1 "Grand Teton / footprint 5622 of 9728 (PEX2), pads 356-474 of 2397")
	)
	(layers
		(0 "F.Cu" signal "TOP")
		(4 "In1.Cu" signal "GND")
		(6 "In2.Cu" signal "VCC")
		(8 "In3.Cu" signal "VCC1")
		(10 "In4.Cu" signal "GND1")
		(12 "In5.Cu" signal "IN1")
		(14 "In6.Cu" signal "GND2")
		(16 "In7.Cu" signal "IN2")
		(18 "In8.Cu" signal "GND3")
		(20 "In9.Cu" signal "IN3")
		(22 "In10.Cu" signal "GND4")
		(24 "In11.Cu" signal "IN4")
		(26 "In12.Cu" signal "GND5")
		(28 "In13.Cu" signal "IN5")
		(30 "In14.Cu" signal "GND6")
		(32 "In15.Cu" signal "IN6")
		(34 "In16.Cu" signal "GND7")
		(2 "B.Cu" signal "BOTTOM")
		(9 "F.Adhes" user "F.Adhesive")
		(11 "B.Adhes" user "B.Adhesive")
		(13 "F.Paste" user "Package Geometry/Pastemask Top")
		(15 "B.Paste" user "Package Geometry/Pastemask Bottom")
		(5 "F.SilkS" user "Ref Des/Silkscreen Top")
		(7 "B.SilkS" user "Ref Des/Silkscreen Bottom")
		(1 "F.Mask" user "Board Geometry/Soldermask Top")
		(3 "B.Mask" user "Board Geometry/Soldermask Bottom")
		(17 "Dwgs.User" user "User.Drawings")
		(19 "Cmts.User" user "User.Comments")
		(21 "Eco1.User" user "User.Eco1")
		(23 "Eco2.User" user "User.Eco2")
		(25 "Edge.Cuts" user "Board Geometry/Outline")
		(27 "Margin" user)
		(31 "F.CrtYd" user "Package Geometry/Place Bound Top")
		(29 "B.CrtYd" user "Package Geometry/Place Bound Bottom")
		(35 "F.Fab" user "Ref Des/Assembly Top")
		(33 "B.Fab" user "Ref Des/Assembly Bottom")
	)
	(footprint ""
		(layer "F.Cu")
		(at 291.84981 -295.89984)
		(property "Reference" "PEX2"
			(at -3.35153 35.56762 0)
			(unlocked yes)
			(layer "F.SilkS")
			(effects
				(font
					(size 2.032 1.524)
					(thickness 0.1524)
				)
				(justify left)
			)
		)
		(property "Value" ""
			(at 0 0 0)
			(layer "F.Fab")
			(effects
				(font
					(size 1.27 1.27)
				)
			)
		)
		(duplicate_pad_numbers_are_jumpers no)
		(pad "AG15" smd circle
			(at -9.500108 1.89992)
			(size 0.4572 0.4572)
			(layers "F.Cu" "F.Mask" "F.Paste")
			(net "P0V8_PEX2")
		)
		(pad "AG16" smd circle
			(at -8.549894 1.89992)
			(size 0.4572 0.4572)
			(layers "F.Cu" "F.Mask" "F.Paste")
			(net "GND")
		)
		(pad "AG17" smd circle
			(at -7.599934 1.89992)
			(size 0.4572 0.4572)
			(layers "F.Cu" "F.Mask" "F.Paste")
			(net "P0V8_PEX2")
		)
		(pad "AG18" smd circle
			(at -6.649974 1.89992)
			(size 0.4572 0.4572)
			(layers "F.Cu" "F.Mask" "F.Paste")
			(net "GND")
		)
		(pad "AG19" smd circle
			(at -5.700014 1.89992)
			(size 0.4572 0.4572)
			(layers "F.Cu" "F.Mask" "F.Paste")
			(net "P0V8_PEX2")
		)
		(pad "AG20" smd circle
			(at -4.750054 1.89992)
			(size 0.4572 0.4572)
			(layers "F.Cu" "F.Mask" "F.Paste")
			(net "GND")
		)
		(pad "AG21" smd circle
			(at -3.800094 1.89992)
			(size 0.4572 0.4572)
			(layers "F.Cu" "F.Mask" "F.Paste")
			(net "P0V8_PEX2")
		)
		(pad "AG22" smd circle
			(at -2.84988 1.89992)
			(size 0.4572 0.4572)
			(layers "F.Cu" "F.Mask" "F.Paste")
			(net "GND")
		)
		(pad "AG23" smd circle
			(at -1.89992 1.89992)
			(size 0.4572 0.4572)
			(layers "F.Cu" "F.Mask" "F.Paste")
			(net "P0V8_PEX2")
		)
		(pad "AG24" smd circle
			(at -0.94996 1.89992)
			(size 0.4572 0.4572)
			(layers "F.Cu" "F.Mask" "F.Paste")
			(net "GND")
		)
		(pad "AG25" smd circle
			(at 0 1.89992)
			(size 0.4572 0.4572)
			(layers "F.Cu" "F.Mask" "F.Paste")
			(net "P0V8_PEX2")
		)
		(pad "AG26" smd circle
			(at 0.94996 1.89992)
			(size 0.4572 0.4572)
			(layers "F.Cu" "F.Mask" "F.Paste")
			(net "GND")
		)
		(pad "AG27" smd circle
			(at 1.89992 1.89992)
			(size 0.4572 0.4572)
			(layers "F.Cu" "F.Mask" "F.Paste")
			(net "P0V8_PEX2")
		)
		(pad "AG28" smd circle
			(at 2.84988 1.89992)
			(size 0.4572 0.4572)
			(layers "F.Cu" "F.Mask" "F.Paste")
			(net "GND")
		)
		(pad "AG29" smd circle
			(at 3.800094 1.89992)
			(size 0.4572 0.4572)
			(layers "F.Cu" "F.Mask" "F.Paste")
			(net "P0V8_PEX2")
		)
		(pad "AG30" smd circle
			(at 4.750054 1.89992)
			(size 0.4572 0.4572)
			(layers "F.Cu" "F.Mask" "F.Paste")
			(net "GND")
		)
		(pad "AG31" smd circle
			(at 5.700014 1.89992)
			(size 0.4572 0.4572)
			(layers "F.Cu" "F.Mask" "F.Paste")
			(net "P0V8_PEX2")
		)
		(pad "AG32" smd circle
			(at 6.649974 1.89992)
			(size 0.4572 0.4572)
			(layers "F.Cu" "F.Mask" "F.Paste")
			(net "GND")
		)
		(pad "AG33" smd circle
			(at 7.599934 1.89992)
			(size 0.4572 0.4572)
			(layers "F.Cu" "F.Mask" "F.Paste")
			(net "P0V8_PEX2")
		)
		(pad "AG34" smd circle
			(at 8.549894 1.89992)
			(size 0.4572 0.4572)
			(layers "F.Cu" "F.Mask" "F.Paste")
			(net "GND")
		)
		(pad "AG35" smd circle
			(at 9.500108 1.89992)
			(size 0.4572 0.4572)
			(layers "F.Cu" "F.Mask" "F.Paste")
			(net "GND")
		)
		(pad "AG36" smd circle
			(at 10.450068 1.89992)
			(size 0.4572 0.4572)
			(layers "F.Cu" "F.Mask" "F.Paste")
			(net "P1V25_PEX2")
		)
		(pad "AG37" smd circle
			(at 11.400028 1.89992)
			(size 0.4572 0.4572)
			(layers "F.Cu" "F.Mask" "F.Paste")
			(net "GND")
		)
		(pad "AG38" smd circle
			(at 12.349988 1.89992)
			(size 0.4572 0.4572)
			(layers "F.Cu" "F.Mask" "F.Paste")
			(net "P1V25_SERDES_VDDPLL_PEX2")
		)
		(pad "AG39" smd circle
			(at 13.299948 1.89992)
			(size 0.4572 0.4572)
			(layers "F.Cu" "F.Mask" "F.Paste")
			(net "GND")
		)
		(pad "AG40" smd circle
			(at 14.249908 1.89992)
			(size 0.4572 0.4572)
			(layers "F.Cu" "F.Mask" "F.Paste")
			(net "GND")
		)
		(pad "AG41" smd circle
			(at 15.200122 1.89992)
			(size 0.4572 0.4572)
			(layers "F.Cu" "F.Mask" "F.Paste")
			(net "GND")
		)
		(pad "AG42" smd circle
			(at 16.150082 1.89992)
			(size 0.4572 0.4572)
			(layers "F.Cu" "F.Mask" "F.Paste")
			(net "GND")
		)
		(pad "AG43" smd circle
			(at 17.100042 1.89992)
			(size 0.4572 0.4572)
			(layers "F.Cu" "F.Mask" "F.Paste")
			(net "Net_1702")
		)
		(pad "AG44" smd circle
			(at 18.050002 1.89992)
			(size 0.4572 0.4572)
			(layers "F.Cu" "F.Mask" "F.Paste")
			(net "Net_1698")
		)
		(pad "AG45" smd circle
			(at 18.999962 1.89992)
			(size 0.4572 0.4572)
			(layers "F.Cu" "F.Mask" "F.Paste")
			(net "GND")
		)
		(pad "AG46" smd circle
			(at 19.949922 1.89992)
			(size 0.4572 0.4572)
			(layers "F.Cu" "F.Mask" "F.Paste")
			(net "Net_1592")
		)
		(pad "AG47" smd circle
			(at 20.899882 1.89992)
			(size 0.4572 0.4572)
			(layers "F.Cu" "F.Mask" "F.Paste")
			(net "Net_1556")
		)
		(pad "AG48" smd circle
			(at 21.850096 1.89992)
			(size 0.4572 0.4572)
			(layers "F.Cu" "F.Mask" "F.Paste")
			(net "GND")
		)
		(pad "AG49" smd circle
			(at 22.800056 1.89992)
			(size 0.4572 0.4572)
			(layers "F.Cu" "F.Mask" "F.Paste")
			(net "GND")
		)
		(pad "AH1" smd circle
			(at -22.800056 2.84988)
			(size 0.4572 0.4572)
			(layers "F.Cu" "F.Mask" "F.Paste")
			(net "GND")
		)
		(pad "AH2" smd circle
			(at -21.850096 2.84988)
			(size 0.4572 0.4572)
			(layers "F.Cu" "F.Mask" "F.Paste")
			(net "GND")
		)
		(pad "AH3" smd circle
			(at -20.899882 2.84988)
			(size 0.4572 0.4572)
			(layers "F.Cu" "F.Mask" "F.Paste")
			(net "GND")
		)
		(pad "AH4" smd circle
			(at -19.949922 2.84988)
			(size 0.4572 0.4572)
			(layers "F.Cu" "F.Mask" "F.Paste")
			(net "Net_5319")
		)
		(pad "AH5" smd circle
			(at -18.999962 2.84988)
			(size 0.4572 0.4572)
			(layers "F.Cu" "F.Mask" "F.Paste")
			(net "Net_5320")
		)
		(pad "AH6" smd circle
			(at -18.050002 2.84988)
			(size 0.4572 0.4572)
			(layers "F.Cu" "F.Mask" "F.Paste")
			(net "GND")
		)
		(pad "AH7" smd circle
			(at -17.100042 2.84988)
			(size 0.4572 0.4572)
			(layers "F.Cu" "F.Mask" "F.Paste")
			(net "SPI_PEX2_CLK")
		)
		(pad "AH8" smd circle
			(at -16.150082 2.84988)
			(size 0.4572 0.4572)
			(layers "F.Cu" "F.Mask" "F.Paste")
			(net "SPI_PEX2_SDIO3")
		)
		(pad "AH9" smd circle
			(at -15.200122 2.84988)
			(size 0.4572 0.4572)
			(layers "F.Cu" "F.Mask" "F.Paste")
			(net "GND")
		)
		(pad "AH10" smd circle
			(at -14.249908 2.84988)
			(size 0.4572 0.4572)
			(layers "F.Cu" "F.Mask" "F.Paste")
			(net "P1V8_PEX")
		)
		(pad "AH11" smd circle
			(at -13.299948 2.84988)
			(size 0.4572 0.4572)
			(layers "F.Cu" "F.Mask" "F.Paste")
			(net "GND")
		)
		(pad "AH12" smd circle
			(at -12.349988 2.84988)
			(size 0.4572 0.4572)
			(layers "F.Cu" "F.Mask" "F.Paste")
			(net "PCEPLL6_VDDA18_PEX2")
		)
		(pad "AH13" smd circle
			(at -11.400028 2.84988)
			(size 0.4572 0.4572)
			(layers "F.Cu" "F.Mask" "F.Paste")
			(net "GND")
		)
		(pad "AH14" smd circle
			(at -10.450068 2.84988)
			(size 0.4572 0.4572)
			(layers "F.Cu" "F.Mask" "F.Paste")
			(net "P0V8_PEX2")
		)
		(pad "AH15" smd circle
			(at -9.500108 2.84988)
			(size 0.4572 0.4572)
			(layers "F.Cu" "F.Mask" "F.Paste")
			(net "GND")
		)
		(pad "AH16" smd circle
			(at -8.549894 2.84988)
			(size 0.4572 0.4572)
			(layers "F.Cu" "F.Mask" "F.Paste")
			(net "P0V8_SERDES_VDDA_PEX2")
		)
		(pad "AH17" smd circle
			(at -7.599934 2.84988)
			(size 0.4572 0.4572)
			(layers "F.Cu" "F.Mask" "F.Paste")
			(net "P0V8_SERDES_VDDA_PEX2")
		)
		(pad "AH18" smd circle
			(at -6.649974 2.84988)
			(size 0.4572 0.4572)
			(layers "F.Cu" "F.Mask" "F.Paste")
			(net "P0V8_SERDES_VDDA_PEX2")
		)
		(pad "AH19" smd circle
			(at -5.700014 2.84988)
			(size 0.4572 0.4572)
			(layers "F.Cu" "F.Mask" "F.Paste")
			(net "P0V8_SERDES_VDDA_PEX2")
		)
		(pad "AH20" smd circle
			(at -4.750054 2.84988)
			(size 0.4572 0.4572)
			(layers "F.Cu" "F.Mask" "F.Paste")
			(net "P0V8_SERDES_VDDA_PEX2")
		)
		(pad "AH21" smd circle
			(at -3.800094 2.84988)
			(size 0.4572 0.4572)
			(layers "F.Cu" "F.Mask" "F.Paste")
			(net "P0V8_SERDES_VDDA_PEX2")
		)
		(pad "AH22" smd circle
			(at -2.84988 2.84988)
			(size 0.4572 0.4572)
			(layers "F.Cu" "F.Mask" "F.Paste")
			(net "P0V8_SERDES_VDDA_PEX2")
		)
		(pad "AH23" smd circle
			(at -1.89992 2.84988)
			(size 0.4572 0.4572)
			(layers "F.Cu" "F.Mask" "F.Paste")
			(net "P0V8_SERDES_VDDA_PEX2")
		)
		(pad "AH24" smd circle
			(at -0.94996 2.84988)
			(size 0.4572 0.4572)
			(layers "F.Cu" "F.Mask" "F.Paste")
			(net "P0V8_SERDES_VDDA_PEX2")
		)
		(pad "AH25" smd circle
			(at 0 2.84988)
			(size 0.4572 0.4572)
			(layers "F.Cu" "F.Mask" "F.Paste")
			(net "P0V8_SERDES_VDDA_PEX2")
		)
		(pad "AH26" smd circle
			(at 0.94996 2.84988)
			(size 0.4572 0.4572)
			(layers "F.Cu" "F.Mask" "F.Paste")
			(net "P0V8_SERDES_VDDA_PEX2")
		)
		(pad "AH27" smd circle
			(at 1.89992 2.84988)
			(size 0.4572 0.4572)
			(layers "F.Cu" "F.Mask" "F.Paste")
			(net "P0V8_SERDES_VDDA_PEX2")
		)
		(pad "AH28" smd circle
			(at 2.84988 2.84988)
			(size 0.4572 0.4572)
			(layers "F.Cu" "F.Mask" "F.Paste")
			(net "P0V8_SERDES_VDDA_PEX2")
		)
		(pad "AH29" smd circle
			(at 3.800094 2.84988)
			(size 0.4572 0.4572)
			(layers "F.Cu" "F.Mask" "F.Paste")
			(net "P0V8_SERDES_VDDA_PEX2")
		)
		(pad "AH30" smd circle
			(at 4.750054 2.84988)
			(size 0.4572 0.4572)
			(layers "F.Cu" "F.Mask" "F.Paste")
			(net "P0V8_SERDES_VDDA_PEX2")
		)
		(pad "AH31" smd circle
			(at 5.700014 2.84988)
			(size 0.4572 0.4572)
			(layers "F.Cu" "F.Mask" "F.Paste")
			(net "P0V8_SERDES_VDDA_PEX2")
		)
		(pad "AH32" smd circle
			(at 6.649974 2.84988)
			(size 0.4572 0.4572)
			(layers "F.Cu" "F.Mask" "F.Paste")
			(net "P0V8_SERDES_VDDA_PEX2")
		)
		(pad "AH33" smd circle
			(at 7.599934 2.84988)
			(size 0.4572 0.4572)
			(layers "F.Cu" "F.Mask" "F.Paste")
			(net "P0V8_SERDES_VDDA_PEX2")
		)
		(pad "AH34" smd circle
			(at 8.549894 2.84988)
			(size 0.4572 0.4572)
			(layers "F.Cu" "F.Mask" "F.Paste")
			(net "GND")
		)
		(pad "AH35" smd circle
			(at 9.500108 2.84988)
			(size 0.4572 0.4572)
			(layers "F.Cu" "F.Mask" "F.Paste")
			(net "GND")
		)
		(pad "AH36" smd circle
			(at 10.450068 2.84988)
			(size 0.4572 0.4572)
			(layers "F.Cu" "F.Mask" "F.Paste")
			(net "GND")
		)
		(pad "AH37" smd circle
			(at 11.400028 2.84988)
			(size 0.4572 0.4572)
			(layers "F.Cu" "F.Mask" "F.Paste")
			(net "GND")
		)
		(pad "AH38" smd circle
			(at 12.349988 2.84988)
			(size 0.4572 0.4572)
			(layers "F.Cu" "F.Mask" "F.Paste")
			(net "GND")
		)
		(pad "AH39" smd circle
			(at 13.299948 2.84988)
			(size 0.4572 0.4572)
			(layers "F.Cu" "F.Mask" "F.Paste")
			(net "GND")
		)
		(pad "AH40" smd circle
			(at 14.249908 2.84988)
			(size 0.4572 0.4572)
			(layers "F.Cu" "F.Mask" "F.Paste")
			(net "GND")
		)
		(pad "AH41" smd circle
			(at 15.200122 2.84988)
			(size 0.4572 0.4572)
			(layers "F.Cu" "F.Mask" "F.Paste")
			(net "Net_1695")
		)
		(pad "AH42" smd circle
			(at 16.150082 2.84988)
			(size 0.4572 0.4572)
			(layers "F.Cu" "F.Mask" "F.Paste")
			(net "Net_1683")
		)
		(pad "AH43" smd circle
			(at 17.100042 2.84988)
			(size 0.4572 0.4572)
			(layers "F.Cu" "F.Mask" "F.Paste")
			(net "GND")
		)
		(pad "AH44" smd circle
			(at 18.050002 2.84988)
			(size 0.4572 0.4572)
			(layers "F.Cu" "F.Mask" "F.Paste")
			(net "GND")
		)
		(pad "AH45" smd circle
			(at 18.999962 2.84988)
			(size 0.4572 0.4572)
			(layers "F.Cu" "F.Mask" "F.Paste")
			(net "GND")
		)
		(pad "AH46" smd circle
			(at 19.949922 2.84988)
			(size 0.4572 0.4572)
			(layers "F.Cu" "F.Mask" "F.Paste")
			(net "GND")
		)
		(pad "AH47" smd circle
			(at 20.899882 2.84988)
			(size 0.4572 0.4572)
			(layers "F.Cu" "F.Mask" "F.Paste")
			(net "GND")
		)
		(pad "AH48" smd circle
			(at 21.850096 2.84988)
			(size 0.4572 0.4572)
			(layers "F.Cu" "F.Mask" "F.Paste")
			(net "Net_1635")
		)
		(pad "AH49" smd circle
			(at 22.800056 2.84988)
			(size 0.4572 0.4572)
			(layers "F.Cu" "F.Mask" "F.Paste")
			(net "Net_1616")
		)
		(pad "AJ1" smd circle
			(at -22.800056 3.800094)
			(size 0.4572 0.4572)
			(layers "F.Cu" "F.Mask" "F.Paste")
			(net "Net_5322")
		)
		(pad "AJ2" smd circle
			(at -21.850096 3.800094)
			(size 0.4572 0.4572)
			(layers "F.Cu" "F.Mask" "F.Paste")
			(net "Net_5323")
		)
		(pad "AJ3" smd circle
			(at -20.899882 3.800094)
			(size 0.4572 0.4572)
			(layers "F.Cu" "F.Mask" "F.Paste")
			(net "GND")
		)
		(pad "AJ4" smd circle
			(at -19.949922 3.800094)
			(size 0.4572 0.4572)
			(layers "F.Cu" "F.Mask" "F.Paste")
			(net "GND")
		)
		(pad "AJ5" smd circle
			(at -18.999962 3.800094)
			(size 0.4572 0.4572)
			(layers "F.Cu" "F.Mask" "F.Paste")
			(net "GND")
		)
		(pad "AJ6" smd circle
			(at -18.050002 3.800094)
			(size 0.4572 0.4572)
			(layers "F.Cu" "F.Mask" "F.Paste")
			(net "GND")
		)
		(pad "AJ7" smd circle
			(at -17.100042 3.800094)
			(size 0.4572 0.4572)
			(layers "F.Cu" "F.Mask" "F.Paste")
			(net "SPI_PEX2_CS_N")
		)
		(pad "AJ8" smd circle
			(at -16.150082 3.800094)
			(size 0.4572 0.4572)
			(layers "F.Cu" "F.Mask" "F.Paste")
			(net "Net_5393")
		)
		(pad "AJ9" smd circle
			(at -15.200122 3.800094)
			(size 0.4572 0.4572)
			(layers "F.Cu" "F.Mask" "F.Paste")
			(net "GND")
		)
		(pad "AJ10" smd circle
			(at -14.249908 3.800094)
			(size 0.4572 0.4572)
			(layers "F.Cu" "F.Mask" "F.Paste")
			(net "P1V8_PEX")
		)
		(pad "AJ11" smd circle
			(at -13.299948 3.800094)
			(size 0.4572 0.4572)
			(layers "F.Cu" "F.Mask" "F.Paste")
			(net "GND")
		)
		(pad "AJ12" smd circle
			(at -12.349988 3.800094)
			(size 0.4572 0.4572)
			(layers "F.Cu" "F.Mask" "F.Paste")
			(net "GND")
		)
		(pad "AJ13" smd circle
			(at -11.400028 3.800094)
			(size 0.4572 0.4572)
			(layers "F.Cu" "F.Mask" "F.Paste")
			(net "PCEPLL7_VDDA18_PEX2")
		)
		(pad "AJ14" smd circle
			(at -10.450068 3.800094)
			(size 0.4572 0.4572)
			(layers "F.Cu" "F.Mask" "F.Paste")
			(net "GND")
		)
		(pad "AJ15" smd circle
			(at -9.500108 3.800094)
			(size 0.4572 0.4572)
			(layers "F.Cu" "F.Mask" "F.Paste")
			(net "P0V8_PEX2")
		)
		(pad "AJ16" smd circle
			(at -8.549894 3.800094)
			(size 0.4572 0.4572)
			(layers "F.Cu" "F.Mask" "F.Paste")
			(net "GND")
		)
		(pad "AJ17" smd circle
			(at -7.599934 3.800094)
			(size 0.4572 0.4572)
			(layers "F.Cu" "F.Mask" "F.Paste")
			(net "GND")
		)
		(pad "AJ18" smd circle
			(at -6.649974 3.800094)
			(size 0.4572 0.4572)
			(layers "F.Cu" "F.Mask" "F.Paste")
			(net "GND")
		)
		(pad "AJ19" smd circle
			(at -5.700014 3.800094)
			(size 0.4572 0.4572)
			(layers "F.Cu" "F.Mask" "F.Paste")
			(net "GND")
		)
		(pad "AJ20" smd circle
			(at -4.750054 3.800094)
			(size 0.4572 0.4572)
			(layers "F.Cu" "F.Mask" "F.Paste")
			(net "GND")
		)
		(pad "AJ21" smd circle
			(at -3.800094 3.800094)
			(size 0.4572 0.4572)
			(layers "F.Cu" "F.Mask" "F.Paste")
			(net "GND")
		)
		(pad "AJ22" smd circle
			(at -2.84988 3.800094)
			(size 0.4572 0.4572)
			(layers "F.Cu" "F.Mask" "F.Paste")
			(net "GND")
		)
		(pad "AJ23" smd circle
			(at -1.89992 3.800094)
			(size 0.4572 0.4572)
			(layers "F.Cu" "F.Mask" "F.Paste")
			(net "GND")
		)
		(pad "AJ24" smd circle
			(at -0.94996 3.800094)
			(size 0.4572 0.4572)
			(layers "F.Cu" "F.Mask" "F.Paste")
			(net "GND")
		)
		(pad "AJ25" smd circle
			(at 0 3.800094)
			(size 0.4572 0.4572)
			(layers "F.Cu" "F.Mask" "F.Paste")
			(net "GND")
		)
		(pad "AJ26" smd circle
			(at 0.94996 3.800094)
			(size 0.4572 0.4572)
			(layers "F.Cu" "F.Mask" "F.Paste")
			(net "GND")
		)
		(pad "AJ27" smd circle
			(at 1.89992 3.800094)
			(size 0.4572 0.4572)
			(layers "F.Cu" "F.Mask" "F.Paste")
			(net "GND")
		)
		(pad "AJ28" smd circle
			(at 2.84988 3.800094)
			(size 0.4572 0.4572)
			(layers "F.Cu" "F.Mask" "F.Paste")
			(net "GND")
		)
		(pad "AJ29" smd circle
			(at 3.800094 3.800094)
			(size 0.4572 0.4572)
			(layers "F.Cu" "F.Mask" "F.Paste")
			(net "GND")
		)
		(pad "AJ30" smd circle
			(at 4.750054 3.800094)
			(size 0.4572 0.4572)
			(layers "F.Cu" "F.Mask" "F.Paste")
			(net "GND")
		)
		(pad "AJ31" smd circle
			(at 5.700014 3.800094)
			(size 0.4572 0.4572)
			(layers "F.Cu" "F.Mask" "F.Paste")
			(net "GND")
		)
		(pad "AJ32" smd circle
			(at 6.649974 3.800094)
			(size 0.4572 0.4572)
			(layers "F.Cu" "F.Mask" "F.Paste")
			(net "GND")
		)
		(pad "AJ33" smd circle
			(at 7.599934 3.800094)
			(size 0.4572 0.4572)
			(layers "F.Cu" "F.Mask" "F.Paste")
			(net "GND")
		)
		(pad "AJ34" smd circle
			(at 8.549894 3.800094)
			(size 0.4572 0.4572)
			(layers "F.Cu" "F.Mask" "F.Paste")
			(net "GND")
		)
		(pad "AJ35" smd circle
			(at 9.500108 3.800094)
			(size 0.4572 0.4572)
			(layers "F.Cu" "F.Mask" "F.Paste")
			(net "GND")
		)
	)
)
